# BASEBOARD_FAB2 (Tioga Pass) — schematic netlist excerpt (pin names and nets, part order shuffled) for the footprints in the layout excerpt that follows; sources: Cadence DE-HDL packaged netlist, KiCad conversion of Wiwynn_Tioga_Pass_MB.brd

J9U1  SCONN288_H44441003  SCONN  pkg PIP  page 80
  \12v\(1)  = P12V_NVDIMM_GHJ
  VSS(93)  = GND
  DQ(4)  = M_H_DQ<4>
  VSS(92)  = GND
  DQ(0)  = M_H_DQ<0>
  VSS(91)  = GND
  DQS9P  = M_H_DQS_DP<9>
  DQS9N  = M_H_DQS_DN<9>
  VSS(90)  = GND
  DQ(6)  = M_H_DQ<6>
  VSS(89)  = GND
  DQ(2)  = M_H_DQ<2>
  VSS(88)  = GND
  DQ(12)  = M_H_DQ<12>
  VSS(87)  = GND
  DQ(8)  = M_H_DQ<8>
  VSS(86)  = GND
  DQS10P  = M_H_DQS_DP<10>
  DQS10N  = M_H_DQS_DN<10>
  VSS(85)  = GND
  DQ(14)  = M_H_DQ<14>
  VSS(84)  = GND
  DQ(10)  = M_H_DQ<10>
  VSS(83)  = GND
  DQ(20)  = M_H_DQ<20>
  VSS(82)  = GND
  DQ(16)  = M_H_DQ<16>
  VSS(81)  = GND
  DQS11P  = M_H_DQS_DP<11>
  DQS11N  = M_H_DQS_DN<11>
  VSS(80)  = GND
  DQ(22)  = M_H_DQ<22>
  VSS(79)  = GND
  DQ(18)  = M_H_DQ<18>
  VSS(78)  = GND
  DQ(28)  = M_H_DQ<28>
  VSS(77)  = GND
  DQ(24)  = M_H_DQ<24>
  VSS(76)  = GND
  DQS12P  = M_H_DQS_DP<12>
  DQS12N  = M_H_DQS_DN<12>
  VSS(75)  = GND
  DQ(30)  = M_H_DQ<30>
  VSS(74)  = GND
  DQ(26)  = M_H_DQ<26>
  VSS(73)  = GND
  CB(4)  = M_H_ECC<4>
  VSS(72)  = GND
  CB(0)  = M_H_ECC<0>
  VSS(71)  = GND
  DQS17P  = M_H_DQS_DP<17>
  DQS17N  = M_H_DQS_DN<17>
  VSS(70)  = GND
  CB(6)  = M_H_ECC<6>
  VSS(69)  = GND
  CB(2)  = M_H_ECC<2>
  VSS(68)  = GND
  RESET_N  = M_GHJ_RST_N
  VDD(25)  = PVDDQ_GHJ
  CKE(0)  = M_H_CKE<2>
  VDD(24)  = PVDDQ_GHJ
  ACT_N  = M_H_ACT_N
  BG(0)  = M_H_BG<0>
  VDD(23)  = PVDDQ_GHJ
  A12  = M_H_MA<12>
  A9  = M_H_MA<9>
  VDD(22)  = PVDDQ_GHJ
  A8  = M_H_MA<8>
  A6  = M_H_MA<6>
  VDD(21)  = PVDDQ_GHJ
  A3  = M_H_MA<3>
  A1  = M_H_MA<1>
  VDD(20)  = PVDDQ_GHJ
  CK0P  = M_H_CLK_DP<2>
  CK0N  = M_H_CLK_DN<2>
  VDD(19)  = PVDDQ_GHJ
  VTT(1)  = PVTT_GHJ
  EVENT_N  = FM_DIMM_EVENT_COD_N
  A0  = M_H_MA<0>
  VDD(18)  = PVDDQ_GHJ
  BA(0)  = M_H_BA<0>
  A16_RAS_N  = M_H_MA<16>
  VDD(17)  = PVDDQ_GHJ
  S0_N  = M_H_CS_N<4>
  VDD(16)  = PVDDQ_GHJ
  A15_CAS_N  = M_H_MA<15>
  ODT(0)  = M_H_ODT<2>
  VDD(15)  = PVDDQ_GHJ
  S1_N  = M_H_CS_N<5>
  VDD(14)  = PVDDQ_GHJ
  ODT(1)  = M_H_ODT<3>
  VDD(13)  = PVDDQ_GHJ
  S2_N_C(0)  = M_H_CS_N<6>
  VSS(67)  = GND
  DQ(36)  = M_H_DQ<36>
  VSS(66)  = GND
  DQ(32)  = M_H_DQ<32>
  VSS(65)  = GND
  DQS13P  = M_H_DQS_DP<13>
  DQS13N  = M_H_DQS_DN<13>
  VSS(64)  = GND
  DQ(38)  = M_H_DQ<38>
  VSS(63)  = GND
  DQ(34)  = M_H_DQ<34>
  VSS(62)  = GND
  DQ(44)  = M_H_DQ<44>
  VSS(61)  = GND
  DQ(40)  = M_H_DQ<40>
  VSS(60)  = GND
  DQS14P  = M_H_DQS_DP<14>
  DQS14N  = M_H_DQS_DN<14>
  VSS(59)  = GND
  DQ(46)  = M_H_DQ<46>
  VSS(58)  = GND
  DQ(42)  = M_H_DQ<42>
  VSS(57)  = GND
  DQ(52)  = M_H_DQ<52>
  VSS(56)  = GND
  DQ(48)  = M_H_DQ<48>
  VSS(55)  = GND
  DQS15P  = M_H_DQS_DP<15>
  DQS15N  = M_H_DQS_DN<15>
  VSS(54)  = GND
  DQ(54)  = M_H_DQ<54>
  VSS(53)  = GND
  DQ(50)  = M_H_DQ<50>
  VSS(52)  = GND
  DQ(60)  = M_H_DQ<60>
  VSS(51)  = GND
  DQ(56)  = M_H_DQ<56>
  VSS(50)  = GND
  DQS16P  = M_H_DQS_DP<16>
  DQS16N  = M_H_DQS_DN<16>
  VSS(49)  = GND
  DQ(62)  = M_H_DQ<62>
  VSS(48)  = GND
  DQ(58)  = M_H_DQ<58>
  VSS(47)  = GND
  SA(0)  = PVPP_GHJ
  SA(1)  = PVPP_GHJ
  SCL  = SMB_DDR_GHJ_VPP_SCL
  VPP(4)  = PVPP_GHJ
  VPP(3)  = PVPP_GHJ
  RFU(2)  = TP_CH_H_DIMM0_RFU_2
  \12v\(0)  = P12V_NVDIMM_GHJ
  VREFCA  = M_H_VREF
  VSS(46)  = GND
  DQ(5)  = M_H_DQ<5>
  VSS(45)  = GND
  DQ(1)  = M_H_DQ<1>
  VSS(44)  = GND
  DQS0N  = M_H_DQS_DN<0>
  DQS0P  = M_H_DQS_DP<0>
  VSS(43)  = GND
  DQ(7)  = M_H_DQ<7>
  VSS(42)  = GND
  DQ(3)  = M_H_DQ<3>
  VSS(41)  = GND
  DQ(13)  = M_H_DQ<13>
  VSS(40)  = GND
  DQ(9)  = M_H_DQ<9>
  VSS(39)  = GND
  DQS1N  = M_H_DQS_DN<1>
  DQS1P  = M_H_DQS_DP<1>
  VSS(38)  = GND
  DQ(15)  = M_H_DQ<15>
  VSS(37)  = GND
  DQ(11)  = M_H_DQ<11>
  VSS(36)  = GND
  DQ(21)  = M_H_DQ<21>
  VSS(35)  = GND
  DQ(17)  = M_H_DQ<17>
  VSS(34)  = GND
  DQS2N  = M_H_DQS_DN<2>
  DQS2P  = M_H_DQS_DP<2>
  VSS(33)  = GND
  DQ(23)  = M_H_DQ<23>
  VSS(32)  = GND
  DQ(19)  = M_H_DQ<19>
  VSS(31)  = GND
  DQ(29)  = M_H_DQ<29>
  VSS(30)  = GND
  DQ(25)  = M_H_DQ<25>
  VSS(29)  = GND
  DQS3N  = M_H_DQS_DN<3>
  DQS3P  = M_H_DQS_DP<3>
  VSS(28)  = GND
  DQ(31)  = M_H_DQ<31>
  VSS(27)  = GND
  DQ(27)  = M_H_DQ<27>
  VSS(26)  = GND
  CB(5)  = M_H_ECC<5>
  VSS(25)  = GND
  CB(1)  = M_H_ECC<1>
  VSS(24)  = GND
  DQS8N  = M_H_DQS_DN<8>
  DQS8P  = M_H_DQS_DP<8>
  VSS(23)  = GND
  CB(7)  = M_H_ECC<7>
  VSS(22)  = GND
  CB(3)  = M_H_ECC<3>
  VSS(21)  = GND
  CKE(1)  = M_H_CKE<3>
  VDD(12)  = PVDDQ_GHJ
  RFU(0)  = TP_CH_H_DIMM0_RFU_0
  VDD(11)  = PVDDQ_GHJ
  BG(1)  = M_H_BG<1>
  ALERT_N  = M_H_ALERT_N
  VDD(10)  = PVDDQ_GHJ
  A11  = M_H_MA<11>
  A7  = M_H_MA<7>
  VDD(9)  = PVDDQ_GHJ
  A5  = M_H_MA<5>
  A4  = M_H_MA<4>
  VDD(8)  = PVDDQ_GHJ
  A2  = M_H_MA<2>
  VDD(7)  = PVDDQ_GHJ
  CK1P  = M_H_CLK_DP<3>
  CK1N  = M_H_CLK_DN<3>
  VDD(6)  = PVDDQ_GHJ
  VTT(0)  = PVTT_GHJ
  PAR  = M_H_PAR
  VDD(5)  = PVDDQ_GHJ
  BA(1)  = M_H_BA<1>
  A10  = M_H_MA<10>
  VDD(4)  = PVDDQ_GHJ
  RFU(1)  = TP_CH_H_DIMM0_RFU_1
  A14_WE_N  = M_H_MA<14>
  VDD(3)  = PVDDQ_GHJ
  SAVE_N_NC  = FM_ADR_COMPLETE_GHJ_N
  VDD(2)  = PVDDQ_GHJ
  A13  = M_H_MA<13>
  VDD(1)  = PVDDQ_GHJ
  A17  = M_H_MA<17>
  C(2)  = M_H_C<2>
  VDD(0)  = PVDDQ_GHJ
  S3_N_C(1)  = M_H_CS_N<7>
  SA(2)  = GND
  VSS(20)  = GND
  DQ(37)  = M_H_DQ<37>
  VSS(19)  = GND
  DQ(33)  = M_H_DQ<33>
  VSS(18)  = GND
  DQS4N  = M_H_DQS_DN<4>
  DQS4P  = M_H_DQS_DP<4>
  VSS(17)  = GND
  DQ(39)  = M_H_DQ<39>
  VSS(16)  = GND
  DQ(35)  = M_H_DQ<35>
  VSS(15)  = GND
  DQ(45)  = M_H_DQ<45>
  VSS(14)  = GND
  DQ(41)  = M_H_DQ<41>
  VSS(13)  = GND
  DQS5N  = M_H_DQS_DN<5>
  DQS5P  = M_H_DQS_DP<5>
  VSS(12)  = GND
  DQ(47)  = M_H_DQ<47>
  VSS(11)  = GND
  DQ(43)  = M_H_DQ<43>
  VSS(10)  = GND
  DQ(53)  = M_H_DQ<53>
  VSS(9)  = GND
  DQ(49)  = M_H_DQ<49>
  VSS(8)  = GND
  DQS6N  = M_H_DQS_DN<6>
  DQS6P  = M_H_DQS_DP<6>
  VSS(7)  = GND
  DQ(55)  = M_H_DQ<55>
  VSS(6)  = GND
  DQ(51)  = M_H_DQ<51>
  VSS(5)  = GND
  DQ(61)  = M_H_DQ<61>
  VSS(4)  = GND
  DQ(57)  = M_H_DQ<57>
  VSS(3)  = GND
  DQS7N  = M_H_DQS_DN<7>
  DQS7P  = M_H_DQS_DP<7>
  VSS(2)  = GND
  DQ(63)  = M_H_DQ<63>
  VSS(1)  = GND
  DQ(59)  = M_H_DQ<59>
  VSS(0)  = GND
  VDDSPD  = PVPP_GHJ
  SDA  = SMB_DDR_GHJ_VPP_SDA
  VPP(1)  = PVPP_GHJ
  VPP(0)  = PVPP_GHJ
  VPP(2)  = PVPP_GHJ

(kicad_pcb
	(version 20260206)
	(generator "pcbnew")
	(generator_version "10.0")
	(general
		(thickness 1.6)
		(legacy_teardrops no)
	)
	(paper "A4")
	(title_block
		(title "Wiwynn_Tioga_Pass_MB.brd")
		(comment 1 "Tioga Pass / footprint 3114 of 4770 (J9U1), pads 51-100 of 291")
	)
	(layers
		(0 "F.Cu" signal "TOP")
		(4 "In1.Cu" signal "L2GND")
		(6 "In2.Cu" signal "L3")
		(8 "In3.Cu" signal "L4GND")
		(10 "In4.Cu" signal "L5")
		(12 "In5.Cu" signal "L6GND")
		(14 "In6.Cu" signal "L7VCC")
		(16 "In7.Cu" signal "L8VCC")
		(18 "In8.Cu" signal "L9GND")
		(20 "In9.Cu" signal "L10")
		(22 "In10.Cu" signal "L11GND")
		(24 "In11.Cu" signal "L12")
		(26 "In12.Cu" signal "L13GND")
		(2 "B.Cu" signal "BOTTOM")
		(9 "F.Adhes" user "F.Adhesive")
		(11 "B.Adhes" user "B.Adhesive")
		(13 "F.Paste" user "Package Geometry/Pastemask Top")
		(15 "B.Paste" user "Package Geometry/Pastemask Bottom")
		(5 "F.SilkS" user "Ref Des/Silkscreen Top")
		(7 "B.SilkS" user "Ref Des/Silkscreen Bottom")
		(1 "F.Mask" user "Board Geometry/Soldermask Top")
		(3 "B.Mask" user "Board Geometry/Soldermask Bottom")
		(17 "Dwgs.User" user "User.Drawings")
		(19 "Cmts.User" user "User.Comments")
		(21 "Eco1.User" user "User.Eco1")
		(23 "Eco2.User" user "User.Eco2")
		(25 "Edge.Cuts" user "Board Geometry/Outline")
		(27 "Margin" user)
		(31 "F.CrtYd" user "Package Geometry/Place Bound Top")
		(29 "B.CrtYd" user "Package Geometry/Place Bound Bottom")
		(35 "F.Fab" user "Ref Des/Assembly Top")
		(33 "B.Fab" user "Ref Des/Assembly Bottom")
	)
	(footprint ""
		(layer "B.Cu")
		(at 29.699458 -15.222982 90)
		(property "Reference" "J9U1"
			(at 2.276348 37.991542 0)
			(unlocked yes)
			(layer "B.SilkS")
			(effects
				(font
					(size 0.7874 0.5842)
					(thickness 0.1524)
				)
				(justify left mirror)
			)
		)
		(property "Value" ""
			(at 0 0 90)
			(layer "B.Fab")
			(effects
				(font
					(size 1.27 1.27)
				)
				(justify mirror)
			)
		)
		(duplicate_pad_numbers_are_jumpers no)
		(pad "48" smd rect
			(at 0 39.949882 270)
			(size 1.8034 0.508)
			(layers "B.Cu" "B.Mask" "B.Paste")
			(net "GND")
		)
		(pad "49" smd rect
			(at 0 40.80002 270)
			(size 1.8034 0.508)
			(layers "B.Cu" "B.Mask" "B.Paste")
			(net "M_H_ECC<0>")
		)
		(pad "50" smd rect
			(at 0 41.649904 270)
			(size 1.8034 0.508)
			(layers "B.Cu" "B.Mask" "B.Paste")
			(net "GND")
		)
		(pad "51" smd rect
			(at 0 42.500042 270)
			(size 1.8034 0.508)
			(layers "B.Cu" "B.Mask" "B.Paste")
			(net "M_H_DQS_DP<17>")
		)
		(pad "52" smd rect
			(at 0 43.349926 270)
			(size 1.8034 0.508)
			(layers "B.Cu" "B.Mask" "B.Paste")
			(net "M_H_DQS_DN<17>")
		)
		(pad "53" smd rect
			(at 0 44.200064 270)
			(size 1.8034 0.508)
			(layers "B.Cu" "B.Mask" "B.Paste")
			(net "GND")
		)
		(pad "54" smd rect
			(at 0 45.049948 270)
			(size 1.8034 0.508)
			(layers "B.Cu" "B.Mask" "B.Paste")
			(net "M_H_ECC<6>")
		)
		(pad "55" smd rect
			(at 0 45.900086 270)
			(size 1.8034 0.508)
			(layers "B.Cu" "B.Mask" "B.Paste")
			(net "GND")
		)
		(pad "56" smd rect
			(at 0 46.74997 270)
			(size 1.8034 0.508)
			(layers "B.Cu" "B.Mask" "B.Paste")
			(net "M_H_ECC<2>")
		)
		(pad "57" smd rect
			(at 0 47.600108 270)
			(size 1.8034 0.508)
			(layers "B.Cu" "B.Mask" "B.Paste")
			(net "GND")
		)
		(pad "58" smd rect
			(at 0 48.449992 270)
			(size 1.8034 0.508)
			(layers "B.Cu" "B.Mask" "B.Paste")
			(net "M_GHJ_RST_N")
		)
		(pad "59" smd rect
			(at 0 49.299876 270)
			(size 1.8034 0.508)
			(layers "B.Cu" "B.Mask" "B.Paste")
			(net "PVDDQ_GHJ")
		)
		(pad "60" smd rect
			(at 0 50.150014 270)
			(size 1.8034 0.508)
			(layers "B.Cu" "B.Mask" "B.Paste")
			(net "M_H_CKE<2>")
		)
		(pad "61" smd rect
			(at 0 50.999898 270)
			(size 1.8034 0.508)
			(layers "B.Cu" "B.Mask" "B.Paste")
			(net "PVDDQ_GHJ")
		)
		(pad "62" smd rect
			(at 0 51.850036 270)
			(size 1.8034 0.508)
			(layers "B.Cu" "B.Mask" "B.Paste")
			(net "M_H_ACT_N")
		)
		(pad "63" smd rect
			(at 0 52.69992 270)
			(size 1.8034 0.508)
			(layers "B.Cu" "B.Mask" "B.Paste")
			(net "M_H_BG<0>")
		)
		(pad "64" smd rect
			(at 0 53.550058 270)
			(size 1.8034 0.508)
			(layers "B.Cu" "B.Mask" "B.Paste")
			(net "PVDDQ_GHJ")
		)
		(pad "65" smd rect
			(at 0 54.399942 270)
			(size 1.8034 0.508)
			(layers "B.Cu" "B.Mask" "B.Paste")
			(net "M_H_MA<12>")
		)
		(pad "66" smd rect
			(at 0 55.25008 270)
			(size 1.8034 0.508)
			(layers "B.Cu" "B.Mask" "B.Paste")
			(net "M_H_MA<9>")
		)
		(pad "67" smd rect
			(at 0 56.099964 270)
			(size 1.8034 0.508)
			(layers "B.Cu" "B.Mask" "B.Paste")
			(net "PVDDQ_GHJ")
		)
		(pad "68" smd rect
			(at 0 56.950102 270)
			(size 1.8034 0.508)
			(layers "B.Cu" "B.Mask" "B.Paste")
			(net "M_H_MA<8>")
		)
		(pad "69" smd rect
			(at 0 57.799986 270)
			(size 1.8034 0.508)
			(layers "B.Cu" "B.Mask" "B.Paste")
			(net "M_H_MA<6>")
		)
		(pad "70" smd rect
			(at 0 58.650124 270)
			(size 1.8034 0.508)
			(layers "B.Cu" "B.Mask" "B.Paste")
			(net "PVDDQ_GHJ")
		)
		(pad "71" smd rect
			(at 0 59.500008 270)
			(size 1.8034 0.508)
			(layers "B.Cu" "B.Mask" "B.Paste")
			(net "M_H_MA<3>")
		)
		(pad "72" smd rect
			(at 0 60.349892 270)
			(size 1.8034 0.508)
			(layers "B.Cu" "B.Mask" "B.Paste")
			(net "M_H_MA<1>")
		)
		(pad "73" smd rect
			(at 0 61.20003 270)
			(size 1.8034 0.508)
			(layers "B.Cu" "B.Mask" "B.Paste")
			(net "PVDDQ_GHJ")
		)
		(pad "74" smd rect
			(at 0 62.049914 270)
			(size 1.8034 0.508)
			(layers "B.Cu" "B.Mask" "B.Paste")
			(net "M_H_CLK_DP<2>")
		)
		(pad "75" smd rect
			(at 0 62.900052 270)
			(size 1.8034 0.508)
			(layers "B.Cu" "B.Mask" "B.Paste")
			(net "M_H_CLK_DN<2>")
		)
		(pad "76" smd rect
			(at 0 63.749936 270)
			(size 1.8034 0.508)
			(layers "B.Cu" "B.Mask" "B.Paste")
			(net "PVDDQ_GHJ")
		)
		(pad "77" smd rect
			(at 0 64.600074 270)
			(size 1.8034 0.508)
			(layers "B.Cu" "B.Mask" "B.Paste")
			(net "PVTT_GHJ")
		)
		(pad "78" smd rect
			(at 0 70.550024 270)
			(size 1.8034 0.508)
			(layers "B.Cu" "B.Mask" "B.Paste")
			(net "FM_DIMM_EVENT_COD_N")
		)
		(pad "79" smd rect
			(at 0 71.399908 270)
			(size 1.8034 0.508)
			(layers "B.Cu" "B.Mask" "B.Paste")
			(net "M_H_MA<0>")
		)
		(pad "80" smd rect
			(at 0 72.250046 270)
			(size 1.8034 0.508)
			(layers "B.Cu" "B.Mask" "B.Paste")
			(net "PVDDQ_GHJ")
		)
		(pad "81" smd rect
			(at 0 73.09993 270)
			(size 1.8034 0.508)
			(layers "B.Cu" "B.Mask" "B.Paste")
			(net "M_H_BA<0>")
		)
		(pad "82" smd rect
			(at 0 73.950068 270)
			(size 1.8034 0.508)
			(layers "B.Cu" "B.Mask" "B.Paste")
			(net "M_H_MA<16>")
		)
		(pad "83" smd rect
			(at 0 74.799952 270)
			(size 1.8034 0.508)
			(layers "B.Cu" "B.Mask" "B.Paste")
			(net "PVDDQ_GHJ")
		)
		(pad "84" smd rect
			(at 0 75.65009 270)
			(size 1.8034 0.508)
			(layers "B.Cu" "B.Mask" "B.Paste")
			(net "M_H_CS_N<4>")
		)
		(pad "85" smd rect
			(at 0 76.499974 270)
			(size 1.8034 0.508)
			(layers "B.Cu" "B.Mask" "B.Paste")
			(net "PVDDQ_GHJ")
		)
		(pad "86" smd rect
			(at 0 77.350112 270)
			(size 1.8034 0.508)
			(layers "B.Cu" "B.Mask" "B.Paste")
			(net "M_H_MA<15>")
		)
		(pad "87" smd rect
			(at 0 78.199996 270)
			(size 1.8034 0.508)
			(layers "B.Cu" "B.Mask" "B.Paste")
			(net "M_H_ODT<2>")
		)
		(pad "88" smd rect
			(at 0 79.04988 270)
			(size 1.8034 0.508)
			(layers "B.Cu" "B.Mask" "B.Paste")
			(net "PVDDQ_GHJ")
		)
		(pad "89" smd rect
			(at 0 79.900018 270)
			(size 1.8034 0.508)
			(layers "B.Cu" "B.Mask" "B.Paste")
			(net "M_H_CS_N<5>")
		)
		(pad "90" smd rect
			(at 0 80.749902 270)
			(size 1.8034 0.508)
			(layers "B.Cu" "B.Mask" "B.Paste")
			(net "PVDDQ_GHJ")
		)
		(pad "91" smd rect
			(at 0 81.60004 270)
			(size 1.8034 0.508)
			(layers "B.Cu" "B.Mask" "B.Paste")
			(net "M_H_ODT<3>")
		)
		(pad "92" smd rect
			(at 0 82.449924 270)
			(size 1.8034 0.508)
			(layers "B.Cu" "B.Mask" "B.Paste")
			(net "PVDDQ_GHJ")
		)
		(pad "93" smd rect
			(at 0 83.300062 270)
			(size 1.8034 0.508)
			(layers "B.Cu" "B.Mask" "B.Paste")
			(net "M_H_CS_N<6>")
		)
		(pad "94" smd rect
			(at 0 84.149946 270)
			(size 1.8034 0.508)
			(layers "B.Cu" "B.Mask" "B.Paste")
			(net "GND")
		)
		(pad "95" smd rect
			(at 0 85.000084 270)
			(size 1.8034 0.508)
			(layers "B.Cu" "B.Mask" "B.Paste")
			(net "M_H_DQ<36>")
		)
		(pad "96" smd rect
			(at 0 85.849968 270)
			(size 1.8034 0.508)
			(layers "B.Cu" "B.Mask" "B.Paste")
			(net "GND")
		)
		(pad "97" smd rect
			(at 0 86.700106 270)
			(size 1.8034 0.508)
			(layers "B.Cu" "B.Mask" "B.Paste")
			(net "M_H_DQ<32>")
		)
	)
)
